(kicad_pcb
	(version 20260206)
	(generator "pcbnew")
	(generator_version "10.0")
	(general
		(thickness 1.6)
		(legacy_teardrops no)
	)
	(paper "A4")
	(title_block
		(title "04192023_DAF0TMB3IC0_F0TG_MB_C_brd_V02_OCP.brd")
		(comment 1 "Grand Teton / footprint 4167 of 8354 (J17), pads 114-226 of 291")
	)
	(layers
		(0 "F.Cu" signal "TOP")
		(4 "In1.Cu" signal "GND")
		(6 "In2.Cu" signal "IN1")
		(8 "In3.Cu" signal "GND1")
		(10 "In4.Cu" signal "IN2")
		(12 "In5.Cu" signal "GND2")
		(14 "In6.Cu" signal "IN3")
		(16 "In7.Cu" signal "GND3")
		(18 "In8.Cu" signal "VCC")
		(20 "In9.Cu" signal "VCC1")
		(22 "In10.Cu" signal "GND4")
		(24 "In11.Cu" signal "IN4")
		(26 "In12.Cu" signal "GND5")
		(28 "In13.Cu" signal "IN5")
		(30 "In14.Cu" signal "GND6")
		(32 "In15.Cu" signal "IN6")
		(34 "In16.Cu" signal "GND7")
		(2 "B.Cu" signal "BOTTOM")
		(9 "F.Adhes" user "F.Adhesive")
		(11 "B.Adhes" user "B.Adhesive")
		(13 "F.Paste" user "Package Geometry/Pastemask Top")
		(15 "B.Paste" user "Package Geometry/Pastemask Bottom")
		(5 "F.SilkS" user "Ref Des/Silkscreen Top")
		(7 "B.SilkS" user "Ref Des/Silkscreen Bottom")
		(1 "F.Mask" user "Board Geometry/Soldermask Top")
		(3 "B.Mask" user "Board Geometry/Soldermask Bottom")
		(17 "Dwgs.User" user "User.Drawings")
		(19 "Cmts.User" user "User.Comments")
		(21 "Eco1.User" user "User.Eco1")
		(23 "Eco2.User" user "User.Eco2")
		(25 "Edge.Cuts" user "Board Geometry/Outline")
		(27 "Margin" user)
		(31 "F.CrtYd" user "Package Geometry/Place Bound Top")
		(29 "B.CrtYd" user "Package Geometry/Place Bound Bottom")
		(35 "F.Fab" user "Ref Des/Assembly Top")
		(33 "B.Fab" user "Ref Des/Assembly Bottom")
	)
	(footprint ""
		(layer "F.Cu")
		(at 290.230052 -255.560068 180)
		(property "Reference" "J17"
			(at -2.2098 -81.984088 0)
			(unlocked yes)
			(layer "F.SilkS")
			(effects
				(font
					(size 0.7874 0.5842)
					(thickness 0.1524)
				)
			)
		)
		(property "Value" ""
			(at 0 0 180)
			(layer "F.Fab")
			(effects
				(font
					(size 1.27 1.27)
				)
			)
		)
		(duplicate_pad_numbers_are_jumpers no)
		(pad "114" smd rect
			(at -2.050034 37.824918 90)
			(size 0.519938 1.4986)
			(layers "F.Cu" "F.Mask" "F.Paste")
			(net "GND")
		)
		(pad "115" smd rect
			(at -2.050034 38.675056 90)
			(size 0.519938 1.4986)
			(layers "F.Cu" "F.Mask" "F.Paste")
			(net "M_C_CPU0_SB_DQS_DP<1>")
		)
		(pad "116" smd rect
			(at -2.050034 39.52494 90)
			(size 0.519938 1.4986)
			(layers "F.Cu" "F.Mask" "F.Paste")
			(net "M_C_CPU0_SB_DQS_DN<1>")
		)
		(pad "117" smd rect
			(at -2.050034 40.375078 90)
			(size 0.519938 1.4986)
			(layers "F.Cu" "F.Mask" "F.Paste")
			(net "GND")
		)
		(pad "118" smd rect
			(at -2.050034 41.224962 90)
			(size 0.519938 1.4986)
			(layers "F.Cu" "F.Mask" "F.Paste")
			(net "M_C_CPU0_SB_DQ<12>")
		)
		(pad "119" smd rect
			(at -2.050034 42.0751 90)
			(size 0.519938 1.4986)
			(layers "F.Cu" "F.Mask" "F.Paste")
			(net "GND")
		)
		(pad "120" smd rect
			(at -2.050034 42.924984 90)
			(size 0.519938 1.4986)
			(layers "F.Cu" "F.Mask" "F.Paste")
			(net "M_C_CPU0_SB_DQ<13>")
		)
		(pad "121" smd rect
			(at -2.050034 43.775122 90)
			(size 0.519938 1.4986)
			(layers "F.Cu" "F.Mask" "F.Paste")
			(net "GND")
		)
		(pad "122" smd rect
			(at -2.050034 44.625006 90)
			(size 0.519938 1.4986)
			(layers "F.Cu" "F.Mask" "F.Paste")
			(net "M_C_CPU0_SB_DQ<16>")
		)
		(pad "123" smd rect
			(at -2.050034 45.47489 90)
			(size 0.519938 1.4986)
			(layers "F.Cu" "F.Mask" "F.Paste")
			(net "GND")
		)
		(pad "124" smd rect
			(at -2.050034 46.325028 90)
			(size 0.519938 1.4986)
			(layers "F.Cu" "F.Mask" "F.Paste")
			(net "M_C_CPU0_SB_DQ<17>")
		)
		(pad "125" smd rect
			(at -2.050034 47.174912 90)
			(size 0.519938 1.4986)
			(layers "F.Cu" "F.Mask" "F.Paste")
			(net "GND")
		)
		(pad "126" smd rect
			(at -2.050034 48.02505 90)
			(size 0.519938 1.4986)
			(layers "F.Cu" "F.Mask" "F.Paste")
			(net "M_C_CPU0_SB_DQS_DP<2>")
		)
		(pad "127" smd rect
			(at -2.050034 48.874934 90)
			(size 0.519938 1.4986)
			(layers "F.Cu" "F.Mask" "F.Paste")
			(net "M_C_CPU0_SB_DQS_DN<2>")
		)
		(pad "128" smd rect
			(at -2.050034 49.725072 90)
			(size 0.519938 1.4986)
			(layers "F.Cu" "F.Mask" "F.Paste")
			(net "GND")
		)
		(pad "129" smd rect
			(at -2.050034 50.574956 90)
			(size 0.519938 1.4986)
			(layers "F.Cu" "F.Mask" "F.Paste")
			(net "M_C_CPU0_SB_DQ<20>")
		)
		(pad "130" smd rect
			(at -2.050034 51.425094 90)
			(size 0.519938 1.4986)
			(layers "F.Cu" "F.Mask" "F.Paste")
			(net "GND")
		)
		(pad "131" smd rect
			(at -2.050034 52.274978 90)
			(size 0.519938 1.4986)
			(layers "F.Cu" "F.Mask" "F.Paste")
			(net "M_C_CPU0_SB_DQ<21>")
		)
		(pad "132" smd rect
			(at -2.050034 53.125116 90)
			(size 0.519938 1.4986)
			(layers "F.Cu" "F.Mask" "F.Paste")
			(net "GND")
		)
		(pad "133" smd rect
			(at -2.050034 53.975 90)
			(size 0.519938 1.4986)
			(layers "F.Cu" "F.Mask" "F.Paste")
			(net "M_C_CPU0_SB_DQ<24>")
		)
		(pad "134" smd rect
			(at -2.050034 54.824884 90)
			(size 0.519938 1.4986)
			(layers "F.Cu" "F.Mask" "F.Paste")
			(net "GND")
		)
		(pad "135" smd rect
			(at -2.050034 55.675022 90)
			(size 0.519938 1.4986)
			(layers "F.Cu" "F.Mask" "F.Paste")
			(net "M_C_CPU0_SB_DQ<25>")
		)
		(pad "136" smd rect
			(at -2.050034 56.524906 90)
			(size 0.519938 1.4986)
			(layers "F.Cu" "F.Mask" "F.Paste")
			(net "GND")
		)
		(pad "137" smd rect
			(at -2.050034 57.375044 90)
			(size 0.519938 1.4986)
			(layers "F.Cu" "F.Mask" "F.Paste")
			(net "M_C_CPU0_SB_DQS_DP<3>")
		)
		(pad "138" smd rect
			(at -2.050034 58.224928 90)
			(size 0.519938 1.4986)
			(layers "F.Cu" "F.Mask" "F.Paste")
			(net "M_C_CPU0_SB_DQS_DN<3>")
		)
		(pad "139" smd rect
			(at -2.050034 59.075066 90)
			(size 0.519938 1.4986)
			(layers "F.Cu" "F.Mask" "F.Paste")
			(net "GND")
		)
		(pad "140" smd rect
			(at -2.050034 59.92495 90)
			(size 0.519938 1.4986)
			(layers "F.Cu" "F.Mask" "F.Paste")
			(net "M_C_CPU0_SB_DQ<28>")
		)
		(pad "141" smd rect
			(at -2.050034 60.775088 90)
			(size 0.519938 1.4986)
			(layers "F.Cu" "F.Mask" "F.Paste")
			(net "GND")
		)
		(pad "142" smd rect
			(at -2.050034 61.624972 90)
			(size 0.519938 1.4986)
			(layers "F.Cu" "F.Mask" "F.Paste")
			(net "M_C_CPU0_SB_DQ<29>")
		)
		(pad "143" smd rect
			(at -2.050034 62.47511 90)
			(size 0.519938 1.4986)
			(layers "F.Cu" "F.Mask" "F.Paste")
			(net "GND")
		)
		(pad "144" smd rect
			(at -2.050034 63.324994 90)
			(size 0.519938 1.4986)
			(layers "F.Cu" "F.Mask" "F.Paste")
			(net "Net_2278")
		)
		(pad "145" smd rect
			(at 2.050034 -63.324994 90)
			(size 0.519938 1.4986)
			(layers "F.Cu" "F.Mask" "F.Paste")
			(net "P12V_MEM_CPU0")
		)
		(pad "146" smd rect
			(at 2.050034 -62.47511 90)
			(size 0.519938 1.4986)
			(layers "F.Cu" "F.Mask" "F.Paste")
			(net "P12V_MEM_CPU0")
		)
		(pad "147" smd rect
			(at 2.050034 -61.624972 90)
			(size 0.519938 1.4986)
			(layers "F.Cu" "F.Mask" "F.Paste")
			(net "PWRGD_CHC_CPU0_DIMM")
		)
		(pad "148" smd rect
			(at 2.050034 -60.775088 90)
			(size 0.519938 1.4986)
			(layers "F.Cu" "F.Mask" "F.Paste")
			(net "PD_CHC_CPU0_DIMM_SAA")
		)
		(pad "149" smd rect
			(at 2.050034 -59.92495 90)
			(size 0.519938 1.4986)
			(layers "F.Cu" "F.Mask" "F.Paste")
			(net "Net_2279")
		)
		(pad "150" smd rect
			(at 2.050034 -59.075066 90)
			(size 0.519938 1.4986)
			(layers "F.Cu" "F.Mask" "F.Paste")
			(net "Net_2280")
		)
		(pad "151" smd rect
			(at 2.050034 -58.224928 90)
			(size 0.519938 1.4986)
			(layers "F.Cu" "F.Mask" "F.Paste")
			(net "GND")
		)
		(pad "152" smd rect
			(at 2.050034 -57.375044 90)
			(size 0.519938 1.4986)
			(layers "F.Cu" "F.Mask" "F.Paste")
			(net "M_C_CPU0_SA_DQ<2>")
		)
		(pad "153" smd rect
			(at 2.050034 -56.524906 90)
			(size 0.519938 1.4986)
			(layers "F.Cu" "F.Mask" "F.Paste")
			(net "GND")
		)
		(pad "154" smd rect
			(at 2.050034 -55.675022 90)
			(size 0.519938 1.4986)
			(layers "F.Cu" "F.Mask" "F.Paste")
			(net "M_C_CPU0_SA_DQ<3>")
		)
		(pad "155" smd rect
			(at 2.050034 -54.824884 90)
			(size 0.519938 1.4986)
			(layers "F.Cu" "F.Mask" "F.Paste")
			(net "GND")
		)
		(pad "156" smd rect
			(at 2.050034 -53.975 90)
			(size 0.519938 1.4986)
			(layers "F.Cu" "F.Mask" "F.Paste")
			(net "M_C_CPU0_SA_DQS_DN<5>")
		)
		(pad "157" smd rect
			(at 2.050034 -53.125116 90)
			(size 0.519938 1.4986)
			(layers "F.Cu" "F.Mask" "F.Paste")
			(net "M_C_CPU0_SA_DQS_DP<5>")
		)
		(pad "158" smd rect
			(at 2.050034 -52.274978 90)
			(size 0.519938 1.4986)
			(layers "F.Cu" "F.Mask" "F.Paste")
			(net "GND")
		)
		(pad "159" smd rect
			(at 2.050034 -51.425094 90)
			(size 0.519938 1.4986)
			(layers "F.Cu" "F.Mask" "F.Paste")
			(net "M_C_CPU0_SA_DQ<6>")
		)
		(pad "160" smd rect
			(at 2.050034 -50.574956 90)
			(size 0.519938 1.4986)
			(layers "F.Cu" "F.Mask" "F.Paste")
			(net "GND")
		)
		(pad "161" smd rect
			(at 2.050034 -49.725072 90)
			(size 0.519938 1.4986)
			(layers "F.Cu" "F.Mask" "F.Paste")
			(net "M_C_CPU0_SA_DQ<7>")
		)
		(pad "162" smd rect
			(at 2.050034 -48.874934 90)
			(size 0.519938 1.4986)
			(layers "F.Cu" "F.Mask" "F.Paste")
			(net "GND")
		)
		(pad "163" smd rect
			(at 2.050034 -48.02505 90)
			(size 0.519938 1.4986)
			(layers "F.Cu" "F.Mask" "F.Paste")
			(net "M_C_CPU0_SA_DQ<10>")
		)
		(pad "164" smd rect
			(at 2.050034 -47.174912 90)
			(size 0.519938 1.4986)
			(layers "F.Cu" "F.Mask" "F.Paste")
			(net "GND")
		)
		(pad "165" smd rect
			(at 2.050034 -46.325028 90)
			(size 0.519938 1.4986)
			(layers "F.Cu" "F.Mask" "F.Paste")
			(net "M_C_CPU0_SA_DQ<11>")
		)
		(pad "166" smd rect
			(at 2.050034 -45.47489 90)
			(size 0.519938 1.4986)
			(layers "F.Cu" "F.Mask" "F.Paste")
			(net "GND")
		)
		(pad "167" smd rect
			(at 2.050034 -44.625006 90)
			(size 0.519938 1.4986)
			(layers "F.Cu" "F.Mask" "F.Paste")
			(net "M_C_CPU0_SA_DQS_DN<6>")
		)
		(pad "168" smd rect
			(at 2.050034 -43.775122 90)
			(size 0.519938 1.4986)
			(layers "F.Cu" "F.Mask" "F.Paste")
			(net "M_C_CPU0_SA_DQS_DP<6>")
		)
		(pad "169" smd rect
			(at 2.050034 -42.924984 90)
			(size 0.519938 1.4986)
			(layers "F.Cu" "F.Mask" "F.Paste")
			(net "GND")
		)
		(pad "170" smd rect
			(at 2.050034 -42.0751 90)
			(size 0.519938 1.4986)
			(layers "F.Cu" "F.Mask" "F.Paste")
			(net "M_C_CPU0_SA_DQ<14>")
		)
		(pad "171" smd rect
			(at 2.050034 -41.224962 90)
			(size 0.519938 1.4986)
			(layers "F.Cu" "F.Mask" "F.Paste")
			(net "GND")
		)
		(pad "172" smd rect
			(at 2.050034 -40.375078 90)
			(size 0.519938 1.4986)
			(layers "F.Cu" "F.Mask" "F.Paste")
			(net "M_C_CPU0_SA_DQ<15>")
		)
		(pad "173" smd rect
			(at 2.050034 -39.52494 90)
			(size 0.519938 1.4986)
			(layers "F.Cu" "F.Mask" "F.Paste")
			(net "GND")
		)
		(pad "174" smd rect
			(at 2.050034 -38.675056 90)
			(size 0.519938 1.4986)
			(layers "F.Cu" "F.Mask" "F.Paste")
			(net "M_C_CPU0_SA_DQ<18>")
		)
		(pad "175" smd rect
			(at 2.050034 -37.824918 90)
			(size 0.519938 1.4986)
			(layers "F.Cu" "F.Mask" "F.Paste")
			(net "GND")
		)
		(pad "176" smd rect
			(at 2.050034 -36.975034 90)
			(size 0.519938 1.4986)
			(layers "F.Cu" "F.Mask" "F.Paste")
			(net "M_C_CPU0_SA_DQ<19>")
		)
		(pad "177" smd rect
			(at 2.050034 -36.124896 90)
			(size 0.519938 1.4986)
			(layers "F.Cu" "F.Mask" "F.Paste")
			(net "GND")
		)
		(pad "178" smd rect
			(at 2.050034 -35.275012 90)
			(size 0.519938 1.4986)
			(layers "F.Cu" "F.Mask" "F.Paste")
			(net "M_C_CPU0_SA_DQS_DN<7>")
		)
		(pad "179" smd rect
			(at 2.050034 -34.425128 90)
			(size 0.519938 1.4986)
			(layers "F.Cu" "F.Mask" "F.Paste")
			(net "M_C_CPU0_SA_DQS_DP<7>")
		)
		(pad "180" smd rect
			(at 2.050034 -33.57499 90)
			(size 0.519938 1.4986)
			(layers "F.Cu" "F.Mask" "F.Paste")
			(net "GND")
		)
		(pad "181" smd rect
			(at 2.050034 -32.725106 90)
			(size 0.519938 1.4986)
			(layers "F.Cu" "F.Mask" "F.Paste")
			(net "M_C_CPU0_SA_DQ<22>")
		)
		(pad "182" smd rect
			(at 2.050034 -31.874968 90)
			(size 0.519938 1.4986)
			(layers "F.Cu" "F.Mask" "F.Paste")
			(net "GND")
		)
		(pad "183" smd rect
			(at 2.050034 -31.025084 90)
			(size 0.519938 1.4986)
			(layers "F.Cu" "F.Mask" "F.Paste")
			(net "M_C_CPU0_SA_DQ<23>")
		)
		(pad "184" smd rect
			(at 2.050034 -30.174946 90)
			(size 0.519938 1.4986)
			(layers "F.Cu" "F.Mask" "F.Paste")
			(net "GND")
		)
		(pad "185" smd rect
			(at 2.050034 -29.325062 90)
			(size 0.519938 1.4986)
			(layers "F.Cu" "F.Mask" "F.Paste")
			(net "M_C_CPU0_SA_DQ<26>")
		)
		(pad "186" smd rect
			(at 2.050034 -28.474924 90)
			(size 0.519938 1.4986)
			(layers "F.Cu" "F.Mask" "F.Paste")
			(net "GND")
		)
		(pad "187" smd rect
			(at 2.050034 -27.62504 90)
			(size 0.519938 1.4986)
			(layers "F.Cu" "F.Mask" "F.Paste")
			(net "M_C_CPU0_SA_DQ<27>")
		)
		(pad "188" smd rect
			(at 2.050034 -26.774902 90)
			(size 0.519938 1.4986)
			(layers "F.Cu" "F.Mask" "F.Paste")
			(net "GND")
		)
		(pad "189" smd rect
			(at 2.050034 -25.925018 90)
			(size 0.519938 1.4986)
			(layers "F.Cu" "F.Mask" "F.Paste")
			(net "M_C_CPU0_SA_DQS_DN<8>")
		)
		(pad "190" smd rect
			(at 2.050034 -25.07488 90)
			(size 0.519938 1.4986)
			(layers "F.Cu" "F.Mask" "F.Paste")
			(net "M_C_CPU0_SA_DQS_DP<8>")
		)
		(pad "191" smd rect
			(at 2.050034 -24.224996 90)
			(size 0.519938 1.4986)
			(layers "F.Cu" "F.Mask" "F.Paste")
			(net "GND")
		)
		(pad "192" smd rect
			(at 2.050034 -23.375112 90)
			(size 0.519938 1.4986)
			(layers "F.Cu" "F.Mask" "F.Paste")
			(net "M_C_CPU0_SA_DQ<30>")
		)
		(pad "193" smd rect
			(at 2.050034 -22.524974 90)
			(size 0.519938 1.4986)
			(layers "F.Cu" "F.Mask" "F.Paste")
			(net "GND")
		)
		(pad "194" smd rect
			(at 2.050034 -21.67509 90)
			(size 0.519938 1.4986)
			(layers "F.Cu" "F.Mask" "F.Paste")
			(net "M_C_CPU0_SA_DQ<31>")
		)
		(pad "195" smd rect
			(at 2.050034 -20.824952 90)
			(size 0.519938 1.4986)
			(layers "F.Cu" "F.Mask" "F.Paste")
			(net "GND")
		)
		(pad "196" smd rect
			(at 2.050034 -19.975068 90)
			(size 0.519938 1.4986)
			(layers "F.Cu" "F.Mask" "F.Paste")
			(net "M_C_CPU0_SA_CB<2>")
		)
		(pad "197" smd rect
			(at 2.050034 -19.12493 90)
			(size 0.519938 1.4986)
			(layers "F.Cu" "F.Mask" "F.Paste")
			(net "GND")
		)
		(pad "198" smd rect
			(at 2.050034 -18.275046 90)
			(size 0.519938 1.4986)
			(layers "F.Cu" "F.Mask" "F.Paste")
			(net "M_C_CPU0_SA_CB<3>")
		)
		(pad "199" smd rect
			(at 2.050034 -17.424908 90)
			(size 0.519938 1.4986)
			(layers "F.Cu" "F.Mask" "F.Paste")
			(net "GND")
		)
		(pad "200" smd rect
			(at 2.050034 -16.575024 90)
			(size 0.519938 1.4986)
			(layers "F.Cu" "F.Mask" "F.Paste")
			(net "M_C_CPU0_SA_DQS_DN<9>")
		)
		(pad "201" smd rect
			(at 2.050034 -15.724886 90)
			(size 0.519938 1.4986)
			(layers "F.Cu" "F.Mask" "F.Paste")
			(net "M_C_CPU0_SA_DQS_DP<9>")
		)
		(pad "202" smd rect
			(at 2.050034 -14.875002 90)
			(size 0.519938 1.4986)
			(layers "F.Cu" "F.Mask" "F.Paste")
			(net "GND")
		)
		(pad "203" smd rect
			(at 2.050034 -14.025118 90)
			(size 0.519938 1.4986)
			(layers "F.Cu" "F.Mask" "F.Paste")
			(net "M_C_CPU0_SA_CB<6>")
		)
		(pad "204" smd rect
			(at 2.050034 -13.17498 90)
			(size 0.519938 1.4986)
			(layers "F.Cu" "F.Mask" "F.Paste")
			(net "GND")
		)
		(pad "205" smd rect
			(at 2.050034 -12.325096 90)
			(size 0.519938 1.4986)
			(layers "F.Cu" "F.Mask" "F.Paste")
			(net "M_C_CPU0_SA_CB<7>")
		)
		(pad "206" smd rect
			(at 2.050034 -11.474958 90)
			(size 0.519938 1.4986)
			(layers "F.Cu" "F.Mask" "F.Paste")
			(net "GND")
		)
		(pad "207" smd rect
			(at 2.050034 -10.625074 90)
			(size 0.519938 1.4986)
			(layers "F.Cu" "F.Mask" "F.Paste")
			(net "M_C_CPU0_RESET_N")
		)
		(pad "208" smd rect
			(at 2.050034 -9.774936 90)
			(size 0.519938 1.4986)
			(layers "F.Cu" "F.Mask" "F.Paste")
			(net "GND")
		)
		(pad "209" smd rect
			(at 2.050034 -8.925052 90)
			(size 0.519938 1.4986)
			(layers "F.Cu" "F.Mask" "F.Paste")
			(net "M_C_CPU0_SA_CS_N<1>")
		)
		(pad "210" smd rect
			(at 2.050034 -8.074914 90)
			(size 0.519938 1.4986)
			(layers "F.Cu" "F.Mask" "F.Paste")
			(net "GND")
		)
		(pad "211" smd rect
			(at 2.050034 -7.22503 90)
			(size 0.519938 1.4986)
			(layers "F.Cu" "F.Mask" "F.Paste")
			(net "M_C_CPU0_SA_CA<1>")
		)
		(pad "212" smd rect
			(at 2.050034 -6.374892 90)
			(size 0.519938 1.4986)
			(layers "F.Cu" "F.Mask" "F.Paste")
			(net "GND")
		)
		(pad "213" smd rect
			(at 2.050034 -5.525008 90)
			(size 0.519938 1.4986)
			(layers "F.Cu" "F.Mask" "F.Paste")
			(net "M_C_CPU0_SA_CA<3>")
		)
		(pad "214" smd rect
			(at 2.050034 -4.675124 90)
			(size 0.519938 1.4986)
			(layers "F.Cu" "F.Mask" "F.Paste")
			(net "GND")
		)
		(pad "215" smd rect
			(at 2.050034 -3.824986 90)
			(size 0.519938 1.4986)
			(layers "F.Cu" "F.Mask" "F.Paste")
			(net "M_C_CPU0_SA_CA<5>")
		)
		(pad "216" smd rect
			(at 2.050034 -2.975102 90)
			(size 0.519938 1.4986)
			(layers "F.Cu" "F.Mask" "F.Paste")
			(net "GND")
		)
		(pad "217" smd rect
			(at 2.050034 -2.124964 90)
			(size 0.519938 1.4986)
			(layers "F.Cu" "F.Mask" "F.Paste")
			(net "M_C_CPU0_CLK_DP<0>")
		)
		(pad "218" smd rect
			(at 2.050034 -1.27508 90)
			(size 0.519938 1.4986)
			(layers "F.Cu" "F.Mask" "F.Paste")
			(net "M_C_CPU0_CLK_DN<0>")
		)
		(pad "219" smd rect
			(at 2.050034 -0.424942 90)
			(size 0.519938 1.4986)
			(layers "F.Cu" "F.Mask" "F.Paste")
			(net "GND")
		)
		(pad "220" smd rect
			(at 2.050034 5.525008 90)
			(size 0.519938 1.4986)
			(layers "F.Cu" "F.Mask" "F.Paste")
			(net "Net_2281")
		)
		(pad "221" smd rect
			(at 2.050034 6.374892 90)
			(size 0.519938 1.4986)
			(layers "F.Cu" "F.Mask" "F.Paste")
			(net "M_C_CPU0_SB_CA<1>")
		)
		(pad "222" smd rect
			(at 2.050034 7.22503 90)
			(size 0.519938 1.4986)
			(layers "F.Cu" "F.Mask" "F.Paste")
			(net "GND")
		)
		(pad "223" smd rect
			(at 2.050034 8.074914 90)
			(size 0.519938 1.4986)
			(layers "F.Cu" "F.Mask" "F.Paste")
			(net "M_C_CPU0_SB_CA<3>")
		)
		(pad "224" smd rect
			(at 2.050034 8.925052 90)
			(size 0.519938 1.4986)
			(layers "F.Cu" "F.Mask" "F.Paste")
			(net "GND")
		)
		(pad "225" smd rect
			(at 2.050034 9.774936 90)
			(size 0.519938 1.4986)
			(layers "F.Cu" "F.Mask" "F.Paste")
			(net "M_C_CPU0_SB_CA<5>")
		)
		(pad "226" smd rect
			(at 2.050034 10.625074 90)
			(size 0.519938 1.4986)
			(layers "F.Cu" "F.Mask" "F.Paste")
			(net "GND")
		)
	)
)
